# S9S_MB_2U (Grand Teton) — schematic netlist excerpt (pin names and nets, part order shuffled) for the footprints in the layout excerpt that follows; sources: Cadence DE-HDL packaged netlist, KiCad conversion of 03242023_DA0F0TMBIJ0_F0T_Motherboard_J_brd_V01_OCP.brd

C1756  Q_CAP  1000PF 50V 5% EMPTY  pkg 0402  page 148 : A = FM_GPU_PWRGD_ISO ; B = GND
R939  Q_RES  10K 1% CHIP  pkg 0402LF  page 128 : A = RST_CPU1_DRAM_GH_N ; B = GND

(kicad_pcb
	(version 20260206)
	(generator "pcbnew")
	(generator_version "10.0")
	(general
		(thickness 1.6)
		(legacy_teardrops no)
	)
	(paper "A4")
	(title_block
		(title "03242023_DA0F0TMBIJ0_F0T_Motherboard_J_brd_V01_OCP.brd")
		(comment 1 "Grand Teton / footprints 2060-2061 of 6105")
	)
	(layers
		(0 "F.Cu" signal "TOP")
		(4 "In1.Cu" signal "GND")
		(6 "In2.Cu" signal "IN1")
		(8 "In3.Cu" signal "GND1")
		(10 "In4.Cu" signal "IN2")
		(12 "In5.Cu" signal "GND2")
		(14 "In6.Cu" signal "IN3")
		(16 "In7.Cu" signal "GND3")
		(18 "In8.Cu" signal "VCC")
		(20 "In9.Cu" signal "VCC1")
		(22 "In10.Cu" signal "GND4")
		(24 "In11.Cu" signal "IN4")
		(26 "In12.Cu" signal "GND5")
		(28 "In13.Cu" signal "IN5")
		(30 "In14.Cu" signal "GND6")
		(32 "In15.Cu" signal "IN6")
		(34 "In16.Cu" signal "GND7")
		(2 "B.Cu" signal "BOTTOM")
		(9 "F.Adhes" user "F.Adhesive")
		(11 "B.Adhes" user "B.Adhesive")
		(13 "F.Paste" user "Package Geometry/Pastemask Top")
		(15 "B.Paste" user "Package Geometry/Pastemask Bottom")
		(5 "F.SilkS" user "Ref Des/Silkscreen Top")
		(7 "B.SilkS" user "Ref Des/Silkscreen Bottom")
		(1 "F.Mask" user "Board Geometry/Soldermask Top")
		(3 "B.Mask" user "Board Geometry/Soldermask Bottom")
		(17 "Dwgs.User" user "User.Drawings")
		(19 "Cmts.User" user "User.Comments")
		(21 "Eco1.User" user "User.Eco1")
		(23 "Eco2.User" user "User.Eco2")
		(25 "Edge.Cuts" user "Board Geometry/Outline")
		(27 "Margin" user)
		(31 "F.CrtYd" user "Package Geometry/Place Bound Top")
		(29 "B.CrtYd" user "Package Geometry/Place Bound Bottom")
		(35 "F.Fab" user "Ref Des/Assembly Top")
		(33 "B.Fab" user "Ref Des/Assembly Bottom")
	)
	(footprint ""
		(layer "F.Cu")
		(at 24.046942 -415.127948 180)
		(property "Reference" "C1756"
			(at 0 0 180)
			(layer "F.SilkS")
			(hide yes)
			(effects
				(font
					(size 1.27 1.27)
				)
			)
		)
		(property "Value" ""
			(at 0 0 180)
			(layer "F.Fab")
			(effects
				(font
					(size 1.27 1.27)
				)
			)
		)
		(duplicate_pad_numbers_are_jumpers no)
		(fp_line
			(start 0.7874 0.4064)
			(end -0.7874 0.4064)
			(stroke
				(width 0.1524)
				(type default)
			)
			(layer "F.SilkS")
		)
		(fp_line
			(start 0.7874 -0.4064)
			(end 0.7874 0.4064)
			(stroke
				(width 0.1524)
				(type default)
			)
			(layer "F.SilkS")
		)
		(fp_line
			(start -0.7874 0.4064)
			(end -0.7874 -0.4064)
			(stroke
				(width 0.1524)
				(type default)
			)
			(layer "F.SilkS")
		)
		(fp_line
			(start -0.7874 -0.4064)
			(end 0.7874 -0.4064)
			(stroke
				(width 0.1524)
				(type default)
			)
			(layer "F.SilkS")
		)
		(fp_line
			(start 0.67945 0.3048)
			(end 0.120396 0.3048)
			(stroke
				(width 0.1)
				(type default)
			)
			(layer "F.Fab")
		)
		(fp_line
			(start 0.67945 -0.3048)
			(end 0.67945 0.3048)
			(stroke
				(width 0.1)
				(type default)
			)
			(layer "F.Fab")
		)
		(fp_line
			(start 0.12065 -0.2794)
			(end 0.12065 -0.3048)
			(stroke
				(width 0.1)
				(type default)
			)
			(layer "F.Fab")
		)
		(fp_line
			(start 0.12065 -0.3048)
			(end 0.67945 -0.3048)
			(stroke
				(width 0.1)
				(type default)
			)
			(layer "F.Fab")
		)
		(fp_line
			(start 0.120396 0.3048)
			(end 0.120396 0.2794)
			(stroke
				(width 0.1)
				(type default)
			)
			(layer "F.Fab")
		)
		(fp_line
			(start 0.120396 0.2794)
			(end -0.12065 0.2794)
			(stroke
				(width 0.1)
				(type default)
			)
			(layer "F.Fab")
		)
		(fp_line
			(start -0.12065 0.3048)
			(end -0.67945 0.3048)
			(stroke
				(width 0.1)
				(type default)
			)
			(layer "F.Fab")
		)
		(fp_line
			(start -0.12065 0.2794)
			(end -0.12065 0.3048)
			(stroke
				(width 0.1)
				(type default)
			)
			(layer "F.Fab")
		)
		(fp_line
			(start -0.12065 -0.2794)
			(end 0.12065 -0.2794)
			(stroke
				(width 0.1)
				(type default)
			)
			(layer "F.Fab")
		)
		(fp_line
			(start -0.12065 -0.305054)
			(end -0.12065 -0.2794)
			(stroke
				(width 0.1)
				(type default)
			)
			(layer "F.Fab")
		)
		(fp_line
			(start -0.67945 0.3048)
			(end -0.67945 -0.305054)
			(stroke
				(width 0.1)
				(type default)
			)
			(layer "F.Fab")
		)
		(fp_line
			(start -0.67945 -0.305054)
			(end -0.12065 -0.305054)
			(stroke
				(width 0.1)
				(type default)
			)
			(layer "F.Fab")
		)
		(pad "1" smd circle
			(at -0.40005 0 180)
			(size 0 0)
			(layers "F.Cu" "F.Mask" "F.Paste")
			(net "FM_GPU_PWRGD_ISO")
		)
		(pad "2" smd circle
			(at 0.40005 0 180)
			(size 0 0)
			(layers "F.Cu" "F.Mask" "F.Paste")
			(net "GND")
		)
	)
	(footprint ""
		(layer "F.Cu")
		(at 126.534926 -122.096784 90)
		(property "Reference" "R939"
			(at 0 0 90)
			(layer "F.SilkS")
			(hide yes)
			(effects
				(font
					(size 1.27 1.27)
				)
			)
		)
		(property "Value" ""
			(at 0 0 90)
			(layer "F.Fab")
			(effects
				(font
					(size 1.27 1.27)
				)
			)
		)
		(duplicate_pad_numbers_are_jumpers no)
		(fp_line
			(start 0.7874 -0.4064)
			(end 0.7874 0.4064)
			(stroke
				(width 0.1524)
				(type default)
			)
			(layer "F.SilkS")
		)
		(fp_line
			(start -0.7874 -0.4064)
			(end 0.7874 -0.4064)
			(stroke
				(width 0.1524)
				(type default)
			)
			(layer "F.SilkS")
		)
		(fp_line
			(start 0.7874 0.4064)
			(end -0.7874 0.4064)
			(stroke
				(width 0.1524)
				(type default)
			)
			(layer "F.SilkS")
		)
		(fp_line
			(start -0.7874 0.4064)
			(end -0.7874 -0.4064)
			(stroke
				(width 0.1524)
				(type default)
			)
			(layer "F.SilkS")
		)
		(fp_line
			(start -0.12065 -0.305054)
			(end -0.12065 -0.2794)
			(stroke
				(width 0.1)
				(type default)
			)
			(layer "F.Fab")
		)
		(fp_line
			(start -0.67945 -0.305054)
			(end -0.12065 -0.305054)
			(stroke
				(width 0.1)
				(type default)
			)
			(layer "F.Fab")
		)
		(fp_line
			(start 0.67945 -0.3048)
			(end 0.67945 0.3048)
			(stroke
				(width 0.1)
				(type default)
			)
			(layer "F.Fab")
		)
		(fp_line
			(start 0.12065 -0.3048)
			(end 0.67945 -0.3048)
			(stroke
				(width 0.1)
				(type default)
			)
			(layer "F.Fab")
		)
		(fp_line
			(start 0.12065 -0.2794)
			(end 0.12065 -0.3048)
			(stroke
				(width 0.1)
				(type default)
			)
			(layer "F.Fab")
		)
		(fp_line
			(start -0.12065 -0.2794)
			(end 0.12065 -0.2794)
			(stroke
				(width 0.1)
				(type default)
			)
			(layer "F.Fab")
		)
		(fp_line
			(start 0.120396 0.2794)
			(end -0.12065 0.2794)
			(stroke
				(width 0.1)
				(type default)
			)
			(layer "F.Fab")
		)
		(fp_line
			(start -0.12065 0.2794)
			(end -0.12065 0.3048)
			(stroke
				(width 0.1)
				(type default)
			)
			(layer "F.Fab")
		)
		(fp_line
			(start 0.67945 0.3048)
			(end 0.120396 0.3048)
			(stroke
				(width 0.1)
				(type default)
			)
			(layer "F.Fab")
		)
		(fp_line
			(start 0.120396 0.3048)
			(end 0.120396 0.2794)
			(stroke
				(width 0.1)
				(type default)
			)
			(layer "F.Fab")
		)
		(fp_line
			(start -0.12065 0.3048)
			(end -0.67945 0.3048)
			(stroke
				(width 0.1)
				(type default)
			)
			(layer "F.Fab")
		)
		(fp_line
			(start -0.67945 0.3048)
			(end -0.67945 -0.305054)
			(stroke
				(width 0.1)
				(type default)
			)
			(layer "F.Fab")
		)
		(pad "1" smd circle
			(at -0.40005 0 90)
			(size 0 0)
			(layers "F.Cu" "F.Mask" "F.Paste")
			(net "RST_CPU1_DRAM_GH_N")
		)
		(pad "2" smd circle
			(at 0.40005 0 90)
			(size 0 0)
			(layers "F.Cu" "F.Mask" "F.Paste")
			(net "GND")
		)
	)
)
